(kicad_pcb
	(version 20221018)
	(generator pcbnew)
	(general
    (thickness 1.7403)
  )
	(paper "A4")
	(title_block
    (title "Data Center RDIMM DDR4 Tester")
    (date "2024-09-30")
    (rev "1.2.4")
		(comment 9 "footprints 422-429 of 690")
	)
	(layers
    (0 "F.Cu" signal)
    (1 "In1.Cu" power)
    (2 "In2.Cu" signal)
    (3 "In3.Cu" power)
    (4 "In4.Cu" power)
    (5 "In5.Cu" signal)
    (6 "In6.Cu" power)
    (7 "In7.Cu" signal)
    (8 "In8.Cu" power)
    (9 "In9.Cu" signal)
    (10 "In10.Cu" power)
    (31 "B.Cu" signal)
    (32 "B.Adhes" user "B.Adhesive")
    (33 "F.Adhes" user "F.Adhesive")
    (34 "B.Paste" user)
    (35 "F.Paste" user)
    (36 "B.SilkS" user "B.Silkscreen")
    (37 "F.SilkS" user "F.Silkscreen")
    (38 "B.Mask" user)
    (39 "F.Mask" user)
    (40 "Dwgs.User" user "User.Drawings")
    (41 "Cmts.User" user "User.Comments")
    (42 "Eco1.User" user "User.Eco1")
    (43 "Eco2.User" user "User.Eco2")
    (44 "Edge.Cuts" user)
    (45 "Margin" user)
    (46 "B.CrtYd" user "B.Courtyard")
    (47 "F.CrtYd" user "F.Courtyard")
    (48 "B.Fab" user)
    (49 "F.Fab" user)
  )
	(footprint "data-center-rdimm-ddr4-tester-footprints:SC70-3" (layer "B.Cu")
    (at 238.9 96.55)
    (property "Author" "Antmicro")
    (property "License" "Apache-2.0")
    (property "MPN" "BSS138PW")
    (property "Manufacturer" "Nexperia")
    (property "Sheetfile" "interfaces.kicad_sch")
    (property "Sheetname" "Interfaces")
    (property "ki_description" "60 V, 320 mA N-channel enhancement mode Trench MOSFET, SC-70-3 aka SOT-323 package")
    (property "ki_keywords" "n-channel enhancement mosfet sc70 sc-70 sot-323 sot323")
    (attr smd)
    (fp_text reference "Q2" (at -1.35 0.41 180) (layer "B.SilkS")
        (effects (font (size 0.7 0.7) (thickness 0.15)) (justify left bottom mirror))
    )
    (fp_text value "BSS138PW" (at 0 -2.3 180) (layer "B.Fab") hide
        (effects (font (size 0.7 0.7) (thickness 0.15)) (justify left bottom mirror))
    )
    (fp_text user "Author: Antmicro" (at -1.45 -5.782 180) (layer "B.Fab") hide
        (effects (font (size 0.7 0.7) (thickness 0.15)) (justify left bottom mirror))
    )
    (fp_text user "License: Apache-2.0" (at -1.45 -6.782 180) (layer "B.Fab") hide
        (effects (font (size 0.7 0.7) (thickness 0.15)) (justify left bottom mirror))
    )
    (fp_text user "${REFERENCE}" (at -1.45 -4.783 180) (layer "B.Fab") hide
        (effects (font (size 0.7 0.7) (thickness 0.15)) (justify left bottom mirror))
    )
    (fp_line (start -0.3 -1) (end 0.627 -1.001)
      (stroke (width 0.15) (type solid)) (layer "B.SilkS"))
    (fp_line (start -0.3 1) (end 0.627 0.999)
      (stroke (width 0.15) (type solid)) (layer "B.SilkS"))
    (fp_line (start 0.627 -0.6) (end 0.627 -1.001)
      (stroke (width 0.15) (type solid)) (layer "B.SilkS"))
    (fp_line (start 0.627 0.6) (end 0.627 0.999)
      (stroke (width 0.15) (type solid)) (layer "B.SilkS"))
    (fp_rect (start 1.4 -1.3) (end -1.4 1.3)
      (stroke (width 0.05) (type solid)) (fill none) (layer "B.CrtYd"))
    (fp_rect (start -0.623 0.999) (end 0.627 -1.001)
      (stroke (width 0.15) (type solid)) (fill none) (layer "B.Fab"))
    (pad "1" smd rect (at -0.95 0.65 270) (size 0.6 0.8) (layers "B.Cu" "B.Paste" "B.Mask")
      (net 67 "USR_LED1") (pinfunction "G") (pintype "bidirectional"))
    (pad "2" smd rect (at -0.95 -0.65 270) (size 0.6 0.8) (layers "B.Cu" "B.Paste" "B.Mask")
      (net 9 "GND") (pinfunction "S") (pintype "bidirectional"))
    (pad "3" smd rect (at 0.95 0 270) (size 0.6 0.8) (layers "B.Cu" "B.Paste" "B.Mask")
      (net 574 "Net-(Q2-D)") (pinfunction "D") (pintype "bidirectional"))
  )
	(footprint "data-center-rdimm-ddr4-tester-footprints:SC70-3" (layer "B.Cu")
    (at 238.9 91.2)
    (property "Author" "Antmicro")
    (property "License" "Apache-2.0")
    (property "MPN" "BSS138PW")
    (property "Manufacturer" "Nexperia")
    (property "Sheetfile" "interfaces.kicad_sch")
    (property "Sheetname" "Interfaces")
    (property "ki_description" "60 V, 320 mA N-channel enhancement mode Trench MOSFET, SC-70-3 aka SOT-323 package")
    (property "ki_keywords" "n-channel enhancement mosfet sc70 sc-70 sot-323 sot323")
    (attr smd)
    (fp_text reference "Q3" (at -1.35 0.41 180) (layer "B.SilkS")
        (effects (font (size 0.7 0.7) (thickness 0.15)) (justify left bottom mirror))
    )
    (fp_text value "BSS138PW" (at 0 -2.3 180) (layer "B.Fab") hide
        (effects (font (size 0.7 0.7) (thickness 0.15)) (justify left bottom mirror))
    )
    (fp_text user "License: Apache-2.0" (at -1.45 -6.782 180) (layer "B.Fab") hide
        (effects (font (size 0.7 0.7) (thickness 0.15)) (justify left bottom mirror))
    )
    (fp_text user "Author: Antmicro" (at -1.45 -5.782 180) (layer "B.Fab") hide
        (effects (font (size 0.7 0.7) (thickness 0.15)) (justify left bottom mirror))
    )
    (fp_text user "${REFERENCE}" (at -1.45 -4.783 180) (layer "B.Fab") hide
        (effects (font (size 0.7 0.7) (thickness 0.15)) (justify left bottom mirror))
    )
    (fp_line (start -0.3 -1) (end 0.627 -1.001)
      (stroke (width 0.15) (type solid)) (layer "B.SilkS"))
    (fp_line (start -0.3 1) (end 0.627 0.999)
      (stroke (width 0.15) (type solid)) (layer "B.SilkS"))
    (fp_line (start 0.627 -0.6) (end 0.627 -1.001)
      (stroke (width 0.15) (type solid)) (layer "B.SilkS"))
    (fp_line (start 0.627 0.6) (end 0.627 0.999)
      (stroke (width 0.15) (type solid)) (layer "B.SilkS"))
    (fp_rect (start 1.4 -1.3) (end -1.4 1.3)
      (stroke (width 0.05) (type solid)) (fill none) (layer "B.CrtYd"))
    (fp_rect (start -0.623 0.999) (end 0.627 -1.001)
      (stroke (width 0.15) (type solid)) (fill none) (layer "B.Fab"))
    (pad "1" smd rect (at -0.95 0.65 270) (size 0.6 0.8) (layers "B.Cu" "B.Paste" "B.Mask")
      (net 68 "USR_LED3") (pinfunction "G") (pintype "bidirectional"))
    (pad "2" smd rect (at -0.95 -0.65 270) (size 0.6 0.8) (layers "B.Cu" "B.Paste" "B.Mask")
      (net 9 "GND") (pinfunction "S") (pintype "bidirectional"))
    (pad "3" smd rect (at 0.95 0 270) (size 0.6 0.8) (layers "B.Cu" "B.Paste" "B.Mask")
      (net 575 "Net-(Q3-D)") (pinfunction "D") (pintype "bidirectional"))
  )
	(footprint "data-center-rdimm-ddr4-tester-footprints:SC70-3" (layer "B.Cu")
    (at 238.9 93.9)
    (property "Author" "Antmicro")
    (property "License" "Apache-2.0")
    (property "MPN" "BSS138PW")
    (property "Manufacturer" "Nexperia")
    (property "Sheetfile" "interfaces.kicad_sch")
    (property "Sheetname" "Interfaces")
    (property "ki_description" "60 V, 320 mA N-channel enhancement mode Trench MOSFET, SC-70-3 aka SOT-323 package")
    (property "ki_keywords" "n-channel enhancement mosfet sc70 sc-70 sot-323 sot323")
    (attr smd)
    (fp_text reference "Q4" (at -1.35 0.41 180) (layer "B.SilkS")
        (effects (font (size 0.7 0.7) (thickness 0.15)) (justify left bottom mirror))
    )
    (fp_text value "BSS138PW" (at 0 -2.3 180) (layer "B.Fab") hide
        (effects (font (size 0.7 0.7) (thickness 0.15)) (justify left bottom mirror))
    )
    (fp_text user "${REFERENCE}" (at -1.45 -4.783 180) (layer "B.Fab") hide
        (effects (font (size 0.7 0.7) (thickness 0.15)) (justify left bottom mirror))
    )
    (fp_text user "Author: Antmicro" (at -1.45 -5.782 180) (layer "B.Fab") hide
        (effects (font (size 0.7 0.7) (thickness 0.15)) (justify left bottom mirror))
    )
    (fp_text user "License: Apache-2.0" (at -1.45 -6.782 180) (layer "B.Fab") hide
        (effects (font (size 0.7 0.7) (thickness 0.15)) (justify left bottom mirror))
    )
    (fp_line (start -0.3 -1) (end 0.627 -1.001)
      (stroke (width 0.15) (type solid)) (layer "B.SilkS"))
    (fp_line (start -0.3 1) (end 0.627 0.999)
      (stroke (width 0.15) (type solid)) (layer "B.SilkS"))
    (fp_line (start 0.627 -0.6) (end 0.627 -1.001)
      (stroke (width 0.15) (type solid)) (layer "B.SilkS"))
    (fp_line (start 0.627 0.6) (end 0.627 0.999)
      (stroke (width 0.15) (type solid)) (layer "B.SilkS"))
    (fp_rect (start 1.4 -1.3) (end -1.4 1.3)
      (stroke (width 0.05) (type solid)) (fill none) (layer "B.CrtYd"))
    (fp_rect (start -0.623 0.999) (end 0.627 -1.001)
      (stroke (width 0.15) (type solid)) (fill none) (layer "B.Fab"))
    (pad "1" smd rect (at -0.95 0.65 270) (size 0.6 0.8) (layers "B.Cu" "B.Paste" "B.Mask")
      (net 70 "USR_LED2") (pinfunction "G") (pintype "bidirectional"))
    (pad "2" smd rect (at -0.95 -0.65 270) (size 0.6 0.8) (layers "B.Cu" "B.Paste" "B.Mask")
      (net 9 "GND") (pinfunction "S") (pintype "bidirectional"))
    (pad "3" smd rect (at 0.95 0 270) (size 0.6 0.8) (layers "B.Cu" "B.Paste" "B.Mask")
      (net 576 "Net-(Q4-D)") (pinfunction "D") (pintype "bidirectional"))
  )
	(footprint "data-center-rdimm-ddr4-tester-footprints:SC70-3" (layer "B.Cu")
    (at 238.94 88.5)
    (property "Author" "Antmicro")
    (property "License" "Apache-2.0")
    (property "MPN" "BSS138PW")
    (property "Manufacturer" "Nexperia")
    (property "Sheetfile" "interfaces.kicad_sch")
    (property "Sheetname" "Interfaces")
    (property "ki_description" "60 V, 320 mA N-channel enhancement mode Trench MOSFET, SC-70-3 aka SOT-323 package")
    (property "ki_keywords" "n-channel enhancement mosfet sc70 sc-70 sot-323 sot323")
    (attr smd)
    (fp_text reference "Q5" (at -1.35 0.41 180) (layer "B.SilkS")
        (effects (font (size 0.7 0.7) (thickness 0.15)) (justify left bottom mirror))
    )
    (fp_text value "BSS138PW" (at 0 -2.3 180) (layer "B.Fab") hide
        (effects (font (size 0.7 0.7) (thickness 0.15)) (justify left bottom mirror))
    )
    (fp_text user "Author: Antmicro" (at -1.45 -5.782 180) (layer "B.Fab") hide
        (effects (font (size 0.7 0.7) (thickness 0.15)) (justify left bottom mirror))
    )
    (fp_text user "License: Apache-2.0" (at -1.45 -6.782 180) (layer "B.Fab") hide
        (effects (font (size 0.7 0.7) (thickness 0.15)) (justify left bottom mirror))
    )
    (fp_text user "${REFERENCE}" (at -1.45 -4.783 180) (layer "B.Fab") hide
        (effects (font (size 0.7 0.7) (thickness 0.15)) (justify left bottom mirror))
    )
    (fp_line (start -0.3 -1) (end 0.627 -1.001)
      (stroke (width 0.15) (type solid)) (layer "B.SilkS"))
    (fp_line (start -0.3 1) (end 0.627 0.999)
      (stroke (width 0.15) (type solid)) (layer "B.SilkS"))
    (fp_line (start 0.627 -0.6) (end 0.627 -1.001)
      (stroke (width 0.15) (type solid)) (layer "B.SilkS"))
    (fp_line (start 0.627 0.6) (end 0.627 0.999)
      (stroke (width 0.15) (type solid)) (layer "B.SilkS"))
    (fp_rect (start 1.4 -1.3) (end -1.4 1.3)
      (stroke (width 0.05) (type solid)) (fill none) (layer "B.CrtYd"))
    (fp_rect (start -0.623 0.999) (end 0.627 -1.001)
      (stroke (width 0.15) (type solid)) (fill none) (layer "B.Fab"))
    (pad "1" smd rect (at -0.95 0.65 270) (size 0.6 0.8) (layers "B.Cu" "B.Paste" "B.Mask")
      (net 72 "USR_LED4") (pinfunction "G") (pintype "bidirectional"))
    (pad "2" smd rect (at -0.95 -0.65 270) (size 0.6 0.8) (layers "B.Cu" "B.Paste" "B.Mask")
      (net 9 "GND") (pinfunction "S") (pintype "bidirectional"))
    (pad "3" smd rect (at 0.95 0 270) (size 0.6 0.8) (layers "B.Cu" "B.Paste" "B.Mask")
      (net 577 "Net-(Q5-D)") (pinfunction "D") (pintype "bidirectional"))
  )
	(footprint "data-center-rdimm-ddr4-tester-footprints:SC70-3" (layer "B.Cu")
    (at 238.94 85.825)
    (property "Author" "Antmicro")
    (property "License" "Apache-2.0")
    (property "MPN" "BSS138PW")
    (property "Manufacturer" "Nexperia")
    (property "Sheetfile" "interfaces.kicad_sch")
    (property "Sheetname" "Interfaces")
    (property "ki_description" "60 V, 320 mA N-channel enhancement mode Trench MOSFET, SC-70-3 aka SOT-323 package")
    (property "ki_keywords" "n-channel enhancement mosfet sc70 sc-70 sot-323 sot323")
    (attr smd)
    (fp_text reference "Q6" (at -1.35 0.41 180) (layer "B.SilkS")
        (effects (font (size 0.7 0.7) (thickness 0.15)) (justify left bottom mirror))
    )
    (fp_text value "BSS138PW" (at 0 -2.3 180) (layer "B.Fab") hide
        (effects (font (size 0.7 0.7) (thickness 0.15)) (justify left bottom mirror))
    )
    (fp_text user "License: Apache-2.0" (at -1.45 -6.782 180) (layer "B.Fab") hide
        (effects (font (size 0.7 0.7) (thickness 0.15)) (justify left bottom mirror))
    )
    (fp_text user "${REFERENCE}" (at -1.45 -4.783 180) (layer "B.Fab") hide
        (effects (font (size 0.7 0.7) (thickness 0.15)) (justify left bottom mirror))
    )
    (fp_text user "Author: Antmicro" (at -1.45 -5.782 180) (layer "B.Fab") hide
        (effects (font (size 0.7 0.7) (thickness 0.15)) (justify left bottom mirror))
    )
    (fp_line (start -0.3 -1) (end 0.627 -1.001)
      (stroke (width 0.15) (type solid)) (layer "B.SilkS"))
    (fp_line (start -0.3 1) (end 0.627 0.999)
      (stroke (width 0.15) (type solid)) (layer "B.SilkS"))
    (fp_line (start 0.627 -0.6) (end 0.627 -1.001)
      (stroke (width 0.15) (type solid)) (layer "B.SilkS"))
    (fp_line (start 0.627 0.6) (end 0.627 0.999)
      (stroke (width 0.15) (type solid)) (layer "B.SilkS"))
    (fp_rect (start 1.4 -1.3) (end -1.4 1.3)
      (stroke (width 0.05) (type solid)) (fill none) (layer "B.CrtYd"))
    (fp_rect (start -0.623 0.999) (end 0.627 -1.001)
      (stroke (width 0.15) (type solid)) (fill none) (layer "B.Fab"))
    (pad "1" smd rect (at -0.95 0.65 270) (size 0.6 0.8) (layers "B.Cu" "B.Paste" "B.Mask")
      (net 74 "USR_LED5") (pinfunction "G") (pintype "bidirectional"))
    (pad "2" smd rect (at -0.95 -0.65 270) (size 0.6 0.8) (layers "B.Cu" "B.Paste" "B.Mask")
      (net 9 "GND") (pinfunction "S") (pintype "bidirectional"))
    (pad "3" smd rect (at 0.95 0 270) (size 0.6 0.8) (layers "B.Cu" "B.Paste" "B.Mask")
      (net 578 "Net-(Q6-D)") (pinfunction "D") (pintype "bidirectional"))
  )
	(footprint "data-center-rdimm-ddr4-tester-footprints:SC70-3" (layer "B.Cu")
    (at 239.6 125.865)
    (property "Author" "Antmicro")
    (property "License" "Apache-2.0")
    (property "MPN" "BSS138PW")
    (property "Manufacturer" "Nexperia")
    (property "Sheetfile" "config-spi.kicad_sch")
    (property "Sheetname" "Config SPI flash")
    (property "ki_description" "60 V, 320 mA N-channel enhancement mode Trench MOSFET, SC-70-3 aka SOT-323 package")
    (property "ki_keywords" "n-channel enhancement mosfet sc70 sc-70 sot-323 sot323")
    (attr smd)
    (fp_text reference "Q8" (at 0.95 1.915 180) (layer "B.SilkS")
        (effects (font (size 0.7 0.7) (thickness 0.15)) (justify left bottom mirror))
    )
    (fp_text value "BSS138PW" (at 0 -2.3 180) (layer "B.Fab") hide
        (effects (font (size 0.7 0.7) (thickness 0.15)) (justify left bottom mirror))
    )
    (fp_text user "${REFERENCE}" (at -1.45 -4.783 180) (layer "B.Fab") hide
        (effects (font (size 0.7 0.7) (thickness 0.15)) (justify left bottom mirror))
    )
    (fp_text user "License: Apache-2.0" (at -1.45 -6.782 180) (layer "B.Fab") hide
        (effects (font (size 0.7 0.7) (thickness 0.15)) (justify left bottom mirror))
    )
    (fp_text user "Author: Antmicro" (at -1.45 -5.782 180) (layer "B.Fab") hide
        (effects (font (size 0.7 0.7) (thickness 0.15)) (justify left bottom mirror))
    )
    (fp_line (start -0.3 -1) (end 0.627 -1.001)
      (stroke (width 0.15) (type solid)) (layer "B.SilkS"))
    (fp_line (start -0.3 1) (end 0.627 0.999)
      (stroke (width 0.15) (type solid)) (layer "B.SilkS"))
    (fp_line (start 0.627 -0.6) (end 0.627 -1.001)
      (stroke (width 0.15) (type solid)) (layer "B.SilkS"))
    (fp_line (start 0.627 0.6) (end 0.627 0.999)
      (stroke (width 0.15) (type solid)) (layer "B.SilkS"))
    (fp_rect (start 1.4 -1.3) (end -1.4 1.3)
      (stroke (width 0.05) (type solid)) (fill none) (layer "B.CrtYd"))
    (fp_rect (start -0.623 0.999) (end 0.627 -1.001)
      (stroke (width 0.15) (type solid)) (fill none) (layer "B.Fab"))
    (pad "1" smd rect (at -0.95 0.65 270) (size 0.6 0.8) (layers "B.Cu" "B.Paste" "B.Mask")
      (net 93 "INIT_B") (pinfunction "G") (pintype "bidirectional"))
    (pad "2" smd rect (at -0.95 -0.65 270) (size 0.6 0.8) (layers "B.Cu" "B.Paste" "B.Mask")
      (net 9 "GND") (pinfunction "S") (pintype "bidirectional"))
    (pad "3" smd rect (at 0.95 0 270) (size 0.6 0.8) (layers "B.Cu" "B.Paste" "B.Mask")
      (net 580 "Net-(Q8-D)") (pinfunction "D") (pintype "bidirectional"))
  )
	(footprint "data-center-rdimm-ddr4-tester-footprints:SC70-3" (layer "B.Cu")
    (at 239.69 123.05)
    (property "Author" "Antmicro")
    (property "License" "Apache-2.0")
    (property "MPN" "BSS138PW")
    (property "Manufacturer" "Nexperia")
    (property "Sheetfile" "config-spi.kicad_sch")
    (property "Sheetname" "Config SPI flash")
    (property "ki_description" "60 V, 320 mA N-channel enhancement mode Trench MOSFET, SC-70-3 aka SOT-323 package")
    (property "ki_keywords" "n-channel enhancement mosfet sc70 sc-70 sot-323 sot323")
    (attr smd)
    (fp_text reference "Q7" (at 2.2 -0.51 180) (layer "B.SilkS")
        (effects (font (size 0.7 0.7) (thickness 0.15)) (justify left bottom mirror))
    )
    (fp_text value "BSS138PW" (at 0 -2.3 180) (layer "B.Fab") hide
        (effects (font (size 0.7 0.7) (thickness 0.15)) (justify left bottom mirror))
    )
    (fp_text user "${REFERENCE}" (at -1.45 -4.783 180) (layer "B.Fab") hide
        (effects (font (size 0.7 0.7) (thickness 0.15)) (justify left bottom mirror))
    )
    (fp_text user "Author: Antmicro" (at -1.45 -5.782 180) (layer "B.Fab") hide
        (effects (font (size 0.7 0.7) (thickness 0.15)) (justify left bottom mirror))
    )
    (fp_text user "License: Apache-2.0" (at -1.45 -6.782 180) (layer "B.Fab") hide
        (effects (font (size 0.7 0.7) (thickness 0.15)) (justify left bottom mirror))
    )
    (fp_line (start -0.3 -1) (end 0.627 -1.001)
      (stroke (width 0.15) (type solid)) (layer "B.SilkS"))
    (fp_line (start -0.3 1) (end 0.627 0.999)
      (stroke (width 0.15) (type solid)) (layer "B.SilkS"))
    (fp_line (start 0.627 -0.6) (end 0.627 -1.001)
      (stroke (width 0.15) (type solid)) (layer "B.SilkS"))
    (fp_line (start 0.627 0.6) (end 0.627 0.999)
      (stroke (width 0.15) (type solid)) (layer "B.SilkS"))
    (fp_rect (start 1.4 -1.3) (end -1.4 1.3)
      (stroke (width 0.05) (type solid)) (fill none) (layer "B.CrtYd"))
    (fp_rect (start -0.623 0.999) (end 0.627 -1.001)
      (stroke (width 0.15) (type solid)) (fill none) (layer "B.Fab"))
    (pad "1" smd rect (at -0.95 0.65 270) (size 0.6 0.8) (layers "B.Cu" "B.Paste" "B.Mask")
      (net 25 "DONE") (pinfunction "G") (pintype "bidirectional"))
    (pad "2" smd rect (at -0.95 -0.65 270) (size 0.6 0.8) (layers "B.Cu" "B.Paste" "B.Mask")
      (net 9 "GND") (pinfunction "S") (pintype "bidirectional"))
    (pad "3" smd rect (at 0.95 0 270) (size 0.6 0.8) (layers "B.Cu" "B.Paste" "B.Mask")
      (net 579 "Net-(Q7-D)") (pinfunction "D") (pintype "bidirectional"))
  )
	(footprint "data-center-rdimm-ddr4-tester-footprints:R_0402_1005Metric" (layer "B.Cu")
    (at 241.6 123.6 90)
    (descr "Resistor SMD 0402")
    (tags "resistor SMD 0402")
    (property "Author" "Antmicro")
    (property "License" "Apache-2.0")
    (property "MPN" "CR0402-FX-3300GLF")
    (property "Manufacturer" "Bourns")
    (property "Sheetfile" "config-spi.kicad_sch")
    (property "Sheetname" "Config SPI flash")
    (property "Tolerance" "1%")
    (property "Val" "330R")
    (property "ki_description" "330R resistor in 0402 package with 1% tolerance")
    (attr smd)
    (fp_text reference "R30" (at 1.02 1.32 270) (layer "B.SilkS")
        (effects (font (size 0.7 0.7) (thickness 0.15)) (justify left bottom mirror))
    )
    (fp_text value "R_330R_0402" (at 0 -1.4 270) (layer "B.Fab") hide
        (effects (font (size 0.7 0.7) (thickness 0.15)) (justify left bottom mirror))
    )
    (fp_text user "License: Apache-2.0" (at -0.95 -5.169 270) (layer "B.Fab") hide
        (effects (font (size 0.7 0.7) (thickness 0.15)) (justify left bottom mirror))
    )
    (fp_text user "Author: Antmicro" (at -0.95 -4.169 270) (layer "B.Fab") hide
        (effects (font (size 0.7 0.7) (thickness 0.15)) (justify left bottom mirror))
    )
    (fp_text user "${REFERENCE}" (at -0.95 -3.168 270) (layer "B.Fab") hide
        (effects (font (size 0.7 0.7) (thickness 0.15)) (justify left bottom mirror))
    )
    (fp_rect (start -0.93 0.47) (end 0.93 -0.47)
      (stroke (width 0.05) (type solid)) (fill none) (layer "B.CrtYd"))
    (fp_rect (start -0.5 0.25) (end 0.5 -0.25)
      (stroke (width 0.15) (type solid)) (fill none) (layer "B.Fab"))
    (pad "1" smd roundrect (at -0.485 0 90) (size 0.59 0.64) (layers "B.Cu" "B.Paste" "B.Mask") (roundrect_rratio 0.25)
      (net 89 "Net-(D1-Pad2)") (pintype "passive"))
    (pad "2" smd roundrect (at 0.485 0 90) (size 0.59 0.64) (layers "B.Cu" "B.Paste" "B.Mask") (roundrect_rratio 0.25)
      (net 579 "Net-(Q7-D)") (pintype "passive"))
  )
)
